FILE_TYPE = CONNECTIVITY;
{Allegro Design Entry HDL 16.6-p007 (v16-6-112F) 10/10/2012}
"PAGE_NUMBER" = 77;
0"NC";
1"M_G_DQS_DN<17:0>";
2"M_G_DQS_DP<17:0>";
3"M_G_DQ<63:0>";
4"M_G_MA<17:0>";
5"M_G_CLK_DN<3:0>";
6"M_G_CLK_DP<3:0>";
7"M_G_BA<1:0>";
8"M_G_CS_N<7:0>";
9"M_G_ECC<7:0>";
10"M_G_CKE<3:0>";
11"M_G_BG<1:0>";
12"M_G_ODT<3:0>";
13"PVDDQ_GHJ\g";
14"PVTT_GHJ\g";
15"GND\g";
16"GND\g";
17"GND\g";
18"PVPP_GHJ\g";
19"PVPP_GHJ\g";
20"P12V_NVDIMM_GHJ\g";
21"GND\g";
22"M_G_MA<6>";
23"M_G_DQS_DN<7>";
24"M_G_DQ<21>";
25"M_G_DQ<58>";
26"M_G_DQ<2>";
27"SMB_DDR_GHJ_VPP_SCL";
28"M_G_DQ<61>";
29"M_G_DQS_DN<6>";
30"M_G_VREF";
31"TP_CH_G_DIMM_G0_RFU_1";
32"TP_CH_G_DIMM_G0_RFU_2";
33"M_G_ECC<1>";
34"TP_CH_G_DIMM_G0_RFU_0";
35"M_G_ACT_N";
36"M_G_ALERT_N";
37"SMB_DDR_GHJ_VPP_SDA";
38"FM_ADR_COMPLETE_GHJ_N";
39"FM_DIMM_EVENT_COD_N";
40"M_G_PAR";
41"M_GHJ_RST_N";
42"M_G_CS_N<0>";
43"M_G_CKE<0>";
44"M_G_ODT<1>";
45"M_G_ODT<0>";
46"M_G_ECC<6>";
47"M_G_MA<10>";
48"M_G_MA<2>";
49"M_G_BA<0>";
50"M_G_BG<1>";
51"M_G_BG<0>";
52"M_G_CLK_DP<1>";
53"M_G_CKE<1>";
54"M_G_ECC<0>";
55"M_G_ECC<3>";
56"M_G_ECC<2>";
57"M_G_ECC<5>";
58"M_G_ECC<4>";
59"M_G_ECC<7>";
60"M_G_MA<9>";
61"M_G_MA<8>";
62"M_G_MA<7>";
63"M_G_MA<5>";
64"M_G_MA<4>";
65"M_G_MA<3>";
66"M_G_MA<1>";
67"M_G_MA<0>";
68"M_G_CS_N<1>";
69"M_G_CS_N<2>";
70"M_G_CS_N<3>";
71"M_G_BA<1>";
72"M_G_CLK_DN<0>";
73"M_G_CLK_DP<0>";
74"M_G_CLK_DN<1>";
75"M_G_C<2>";
76"M_G_DQ<5>";
77"M_G_DQ<3>";
78"M_G_DQ<1>";
79"M_G_DQ<0>";
80"M_G_DQ<4>";
81"M_G_DQ<14>";
82"M_G_DQ<7>";
83"M_G_DQ<9>";
84"M_G_DQ<8>";
85"M_G_DQ<11>";
86"M_G_DQ<10>";
87"M_G_DQ<13>";
88"M_G_DQ<12>";
89"M_G_DQ<15>";
90"M_G_DQ<6>";
91"M_G_DQ<19>";
92"M_G_DQ<18>";
93"M_G_DQ<20>";
94"M_G_DQ<23>";
95"M_G_DQ<22>";
96"M_G_DQ<25>";
97"M_G_DQ<24>";
98"M_G_DQ<17>";
99"M_G_DQ<16>";
100"M_G_DQ<27>";
101"M_G_DQ<34>";
102"M_G_DQ<31>";
103"M_G_DQ<30>";
104"M_G_DQ<33>";
105"M_G_DQ<32>";
106"M_G_DQ<35>";
107"M_G_DQ<29>";
108"M_G_DQ<28>";
109"M_G_DQ<26>";
110"M_G_DQ<39>";
111"M_G_DQ<37>";
112"M_G_DQ<36>";
113"M_G_DQ<41>";
114"M_G_DQ<43>";
115"M_G_DQ<44>";
116"M_G_DQ<47>";
117"M_G_DQ<45>";
118"M_G_DQ<42>";
119"M_G_DQ<40>";
120"M_G_DQ<38>";
121"M_G_DQ<46>";
122"M_G_DQ<50>";
123"M_G_DQ<53>";
124"M_G_DQ<52>";
125"M_G_DQ<55>";
126"M_G_DQ<54>";
127"M_G_DQ<57>";
128"M_G_DQ<51>";
129"M_G_DQ<48>";
130"M_G_DQ<49>";
131"M_G_MA<16>";
132"M_G_MA<15>";
133"M_G_MA<14>";
134"M_G_MA<11>";
135"M_G_MA<17>";
136"M_G_MA<13>";
137"M_G_MA<12>";
138"M_G_DQ<62>";
139"M_G_DQ<63>";
140"M_G_DQ<60>";
141"M_G_DQ<59>";
142"M_G_DQ<56>";
143"M_G_DQS_DP<7>";
144"M_G_DQS_DP<6>";
145"M_G_DQS_DP<5>";
146"M_G_DQS_DN<5>";
147"M_G_DQS_DP<4>";
148"M_G_DQS_DN<4>";
149"M_G_DQS_DP<3>";
150"M_G_DQS_DN<3>";
151"M_G_DQS_DP<2>";
152"M_G_DQS_DN<2>";
153"M_G_DQS_DP<1>";
154"M_G_DQS_DN<1>";
155"M_G_DQS_DP<0>";
156"M_G_DQS_DN<0>";
157"M_G_DQS_DP<17>";
158"M_G_DQS_DP<9>";
159"M_G_DQS_DN<9>";
160"M_G_DQS_DP<8>";
161"M_G_DQS_DN<8>";
162"M_G_DQS_DN<17>";
163"M_G_DQS_DP<16>";
164"M_G_DQS_DN<16>";
165"M_G_DQS_DP<15>";
166"M_G_DQS_DN<15>";
167"M_G_DQS_DP<14>";
168"M_G_DQS_DN<14>";
169"M_G_DQS_DP<13>";
170"M_G_DQS_DN<13>";
171"M_G_DQS_DP<12>";
172"M_G_DQS_DN<12>";
173"M_G_DQS_DP<11>";
174"M_G_DQS_DN<11>";
175"M_G_DQS_DP<10>";
176"M_G_DQS_DN<10>";
%"TAP"
"6","(700,4750)","2","mstr_standard","I10";
;
CDS_LIB"mstr_standard"
BODY_TYPE"PLUMBING"
HDL_TAP"TRUE";
"B \NAC \NWC"2;
"S \NAC"
BN"14"167;
%"TAP"
"6","(-1625,1775)","2","mstr_standard","I100";
;
CDS_LIB"mstr_standard"
BODY_TYPE"PLUMBING"
HDL_TAP"TRUE";
"B \NAC \NWC"3;
"S \NAC"
BN"11"85;
%"TAP"
"6","(-1625,1725)","2","mstr_standard","I101";
;
CDS_LIB"mstr_standard"
BODY_TYPE"PLUMBING"
HDL_TAP"TRUE";
"B \NAC \NWC"3;
"S \NAC"
BN"8"84;
%"TAP"
"6","(-1625,1675)","2","mstr_standard","I102";
;
CDS_LIB"mstr_standard"
BODY_TYPE"PLUMBING"
HDL_TAP"TRUE";
"B \NAC \NWC"3;
"S \NAC"
BN"9"83;
%"TAP"
"6","(-1625,1575)","2","mstr_standard","I103";
;
CDS_LIB"mstr_standard"
BODY_TYPE"PLUMBING"
HDL_TAP"TRUE";
"B \NAC \NWC"3;
"S \NAC"
BN"7"82;
%"TAP"
"6","(-1625,1625)","2","mstr_standard","I104";
;
CDS_LIB"mstr_standard"
BODY_TYPE"PLUMBING"
HDL_TAP"TRUE";
"B \NAC \NWC"3;
"S \NAC"
BN"6"90;
%"TAP"
"6","(-1625,1425)","2","mstr_standard","I105";
;
CDS_LIB"mstr_standard"
BODY_TYPE"PLUMBING"
HDL_TAP"TRUE";
"B \NAC \NWC"3;
"S \NAC"
BN"2"26;
%"TAP"
"6","(-1625,1475)","2","mstr_standard","I106";
;
CDS_LIB"mstr_standard"
BODY_TYPE"PLUMBING"
HDL_TAP"TRUE";
"B \NAC \NWC"3;
"S \NAC"
BN"5"76;
%"TAP"
"6","(-1625,1525)","2","mstr_standard","I107";
;
CDS_LIB"mstr_standard"
BODY_TYPE"PLUMBING"
HDL_TAP"TRUE";
"B \NAC \NWC"3;
"S \NAC"
BN"4"80;
%"TAP"
"6","(-1625,1325)","2","mstr_standard","I108";
;
CDS_LIB"mstr_standard"
BODY_TYPE"PLUMBING"
HDL_TAP"TRUE";
"B \NAC \NWC"3;
"S \NAC"
BN"0"79;
%"TAP"
"6","(-1625,1275)","2","mstr_standard","I109";
;
CDS_LIB"mstr_standard"
BODY_TYPE"PLUMBING"
HDL_TAP"TRUE";
"B \NAC \NWC"3;
"S \NAC"
BN"1"78;
%"TAP"
"6","(700,4850)","2","mstr_standard","I11";
;
CDS_LIB"mstr_standard"
BODY_TYPE"PLUMBING"
HDL_TAP"TRUE";
"B \NAC \NWC"2;
"S \NAC"
BN"15"165;
%"TAP"
"6","(-1625,1375)","2","mstr_standard","I110";
;
CDS_LIB"mstr_standard"
BODY_TYPE"PLUMBING"
HDL_TAP"TRUE";
"B \NAC \NWC"3;
"S \NAC"
BN"3"77;
%"SCONN288_H44441004"
"1","(-2375,2775)","0","mstr_sconn","I111";
;
CDS_SEC"1"
LOCATION"J1G1"
PART_NUMBER"H44441-004"
MATERIAL"SCONN"
PACK_TYPE"PIP"
BOM_COST"MEM"
CDS_LIB"mstr_sconn"
SEC_TYPE"PIP"
SEC"1"
CDS_LOCATION"J1G1"
ROOM"DDR4_CH_G";
"DQ<63>"
$PN"280"138;
"DQ<62>"
$PN"135"139;
"DQ<61>"
$PN"273"140;
"DQ<5>"
$PN"148"80;
"DQ<4>"
$PN"3"76;
"DQ<3>"
$PN"157"26;
"DQ<2>"
$PN"12"77;
"DQ<47>"
$PN"258"121;
"DQ<48>"
$PN"119"130;
"DQ<49>"
$PN"264"129;
"DQ<50>"
$PN"126"128;
"DQ<51>"
$PN"271"122;
"DQ<52>"
$PN"117"123;
"DQ<53>"
$PN"262"124;
"DQ<54>"
$PN"124"125;
"DQ<58>"
$PN"137"141;
"DQ<57>"
$PN"275"142;
"SAVE_N_NC"
$PN"230"38;
"RFU<1>"
$PN"227"31;
"RFU<0>"
$PN"205"34;
"DQ<17>"
$PN"172"99;
"DQ<15>"
$PN"166"81;
"DQ<26>"
$PN"45"100;
"DQ<27>"
$PN"190"109;
"S0_N"
$PN"84"42;
"CKE<0>"
$PN"60"43;
"ODT<1>"
$PN"91"44;
"ODT<0>"
$PN"87"45;
"CB<7>"
$PN"199"46;
"A16_RAS_N"
$PN"82"131;
"A15_CAS_N"
$PN"86"132;
"A14_WE_N"
$PN"228"133;
"A11"
$PN"210"134;
"A10"
$PN"225"47;
"DQ<38>"
$PN"102"110;
"DQ<36>"
$PN"95"111;
"DQ<35>"
$PN"249"101;
"A2"
$PN"216"48;
"ALERT_N"
$PN"208"36;
"ACT_N"
$PN"62"35;
"DQ<0>"
$PN"5"78;
"DQ<1>"
$PN"150"79;
"SA<1>"
$PN"140"16;
"SA<2>"
$PN"238"16;
"VDDSPD"
$PN"284"19;
"SA<0>"
$PN"139"16;
"BA<0>"
$PN"81"49;
"BG<1>"
$PN"207"50;
"BG<0>"
$PN"63"51;
"CK1P"
$PN"218"52;
"VREFCA"
$PN"146"30;
"SDA"
$PN"285"37;
"SCL"
$PN"141"27;
"RFU<2>"
$PN"144"32;
"RESET_N"
$PN"58"41;
"PAR"
$PN"222"40;
"EVENT_N"
$PN"78"39;
"DQ<6>"
$PN"10"82;
"DQ<7>"
$PN"155"90;
"DQ<8>"
$PN"16"83;
"DQ<9>"
$PN"161"84;
"DQ<10>"
$PN"23"85;
"DQ<11>"
$PN"168"86;
"DQ<12>"
$PN"14"87;
"DQ<13>"
$PN"159"88;
"DQ<14>"
$PN"21"89;
"DQ<16>"
$PN"27"98;
"DQ<18>"
$PN"34"91;
"DQ<19>"
$PN"179"92;
"DQ<20>"
$PN"25"24;
"DQ<21>"
$PN"170"93;
"DQ<22>"
$PN"32"94;
"DQ<23>"
$PN"177"95;
"DQ<24>"
$PN"38"96;
"DQ<25>"
$PN"183"97;
"DQ<30>"
$PN"43"102;
"DQ<31>"
$PN"188"103;
"DQ<32>"
$PN"97"104;
"DQ<33>"
$PN"242"105;
"DQ<34>"
$PN"104"106;
"DQ<37>"
$PN"240"112;
"DQ<39>"
$PN"247"120;
"DQ<40>"
$PN"108"113;
"DQ<41>"
$PN"253"119;
"DQ<42>"
$PN"115"114;
"DQ<43>"
$PN"260"118;
"DQ<44>"
$PN"106"117;
"DQ<45>"
$PN"251"115;
"DQ<46>"
$PN"113"116;
"DQ<55>"
$PN"269"126;
"DQ<56>"
$PN"130"127;
"DQ<59>"
$PN"282"25;
"DQ<60>"
$PN"128"28;
"CKE<1>"
$PN"203"53;
"CK0N"
$PN"75"72;
"CB<0>"
$PN"49"33;
"CB<1>"
$PN"194"54;
"CB<2>"
$PN"56"55;
"CB<3>"
$PN"201"56;
"CB<4>"
$PN"47"57;
"CB<5>"
$PN"192"58;
"CB<6>"
$PN"54"59;
"A9"
$PN"66"60;
"A8"
$PN"68"61;
"A7"
$PN"211"62;
"A6"
$PN"69"22;
"A5"
$PN"213"63;
"A4"
$PN"214"64;
"A3"
$PN"71"65;
"A17"
$PN"234"135;
"A13"
$PN"232"136;
"A12"
$PN"65"137;
"A1"
$PN"72"66;
"A0"
$PN"79"67;
"C<2>"
$PN"235"75;
"DQ<28>"
$PN"36"107;
"DQ<29>"
$PN"181"108;
"S1_N"
$PN"89"68;
"S2_N_C<0>"
$PN"93"69;
"S3_N_C<1>"
$PN"237"70;
"CK0P"
$PN"74"73;
"CK1N"
$PN"219"74;
"BA<1>"
$PN"224"71;
%"TAP"
"6","(-3125,4425)","0","mstr_standard","I112";
;
CDS_LIB"mstr_standard"
BODY_TYPE"PLUMBING"
HDL_TAP"TRUE";
"B \NAC \NWC"4;
"S \NAC"
BN"17"135;
%"TAP"
"6","(-3125,4375)","0","mstr_standard","I113";
;
CDS_LIB"mstr_standard"
BODY_TYPE"PLUMBING"
HDL_TAP"TRUE";
"B \NAC \NWC"4;
"S \NAC"
BN"16"131;
%"TAP"
"6","(-3125,4325)","0","mstr_standard","I114";
;
CDS_LIB"mstr_standard"
BODY_TYPE"PLUMBING"
HDL_TAP"TRUE";
"B \NAC \NWC"4;
"S \NAC"
BN"15"132;
%"TAP"
"6","(-3125,4275)","0","mstr_standard","I115";
;
CDS_LIB"mstr_standard"
BODY_TYPE"PLUMBING"
HDL_TAP"TRUE";
"B \NAC \NWC"4;
"S \NAC"
BN"14"133;
%"TAP"
"6","(-3125,4125)","0","mstr_standard","I116";
;
CDS_LIB"mstr_standard"
BODY_TYPE"PLUMBING"
HDL_TAP"TRUE";
"B \NAC \NWC"4;
"S \NAC"
BN"11"134;
%"TAP"
"6","(-3125,4225)","0","mstr_standard","I117";
;
CDS_LIB"mstr_standard"
BODY_TYPE"PLUMBING"
HDL_TAP"TRUE";
"B \NAC \NWC"4;
"S \NAC"
BN"13"136;
%"TAP"
"6","(-3125,4175)","0","mstr_standard","I118";
;
CDS_LIB"mstr_standard"
BODY_TYPE"PLUMBING"
HDL_TAP"TRUE";
"B \NAC \NWC"4;
"S \NAC"
BN"12"137;
%"TAP"
"6","(-3125,4075)","0","mstr_standard","I119";
;
CDS_LIB"mstr_standard"
BODY_TYPE"PLUMBING"
HDL_TAP"TRUE";
"B \NAC \NWC"4;
"S \NAC"
BN"10"47;
%"TAP"
"6","(700,4950)","2","mstr_standard","I12";
;
CDS_LIB"mstr_standard"
BODY_TYPE"PLUMBING"
HDL_TAP"TRUE";
"B \NAC \NWC"2;
"S \NAC"
BN"16"163;
%"TAP"
"6","(-3125,4025)","0","mstr_standard","I120";
;
CDS_LIB"mstr_standard"
BODY_TYPE"PLUMBING"
HDL_TAP"TRUE";
"B \NAC \NWC"4;
"S \NAC"
BN"9"60;
%"TAP"
"6","(-3125,3875)","0","mstr_standard","I121";
;
CDS_LIB"mstr_standard"
BODY_TYPE"PLUMBING"
HDL_TAP"TRUE";
"B \NAC \NWC"4;
"S \NAC"
BN"6"22;
%"TAP"
"6","(-3125,3975)","0","mstr_standard","I122";
;
CDS_LIB"mstr_standard"
BODY_TYPE"PLUMBING"
HDL_TAP"TRUE";
"B \NAC \NWC"4;
"S \NAC"
BN"8"61;
%"TAP"
"6","(-3125,3925)","0","mstr_standard","I123";
;
CDS_LIB"mstr_standard"
BODY_TYPE"PLUMBING"
HDL_TAP"TRUE";
"B \NAC \NWC"4;
"S \NAC"
BN"7"62;
%"TAP"
"6","(-3125,3825)","0","mstr_standard","I124";
;
CDS_LIB"mstr_standard"
BODY_TYPE"PLUMBING"
HDL_TAP"TRUE";
"B \NAC \NWC"4;
"S \NAC"
BN"5"63;
%"TAP"
"6","(-3125,3775)","0","mstr_standard","I125";
;
CDS_LIB"mstr_standard"
BODY_TYPE"PLUMBING"
HDL_TAP"TRUE";
"B \NAC \NWC"4;
"S \NAC"
BN"4"64;
%"TAP"
"6","(-3125,3725)","0","mstr_standard","I126";
;
CDS_LIB"mstr_standard"
BODY_TYPE"PLUMBING"
HDL_TAP"TRUE";
"B \NAC \NWC"4;
"S \NAC"
BN"3"65;
%"TAP"
"6","(-3125,3675)","0","mstr_standard","I127";
;
CDS_LIB"mstr_standard"
BODY_TYPE"PLUMBING"
HDL_TAP"TRUE";
"B \NAC \NWC"4;
"S \NAC"
BN"2"48;
%"TAP"
"6","(-3125,3625)","0","mstr_standard","I128";
;
CDS_LIB"mstr_standard"
BODY_TYPE"PLUMBING"
HDL_TAP"TRUE";
"B \NAC \NWC"4;
"S \NAC"
BN"1"66;
%"TAP"
"6","(-3125,3575)","0","mstr_standard","I129";
;
CDS_LIB"mstr_standard"
BODY_TYPE"PLUMBING"
HDL_TAP"TRUE";
"B \NAC \NWC"4;
"S \NAC"
BN"0"67;
%"TAP"
"6","(700,4450)","2","mstr_standard","I13";
;
CDS_LIB"mstr_standard"
BODY_TYPE"PLUMBING"
HDL_TAP"TRUE";
"B \NAC \NWC"2;
"S \NAC"
BN"11"173;
%"TAP"
"6","(-3125,3475)","0","mstr_standard","I130";
;
CDS_LIB"mstr_standard"
BODY_TYPE"PLUMBING"
HDL_TAP"TRUE";
"B \NAC \NWC"7;
"S \NAC"
BN"1"71;
%"TAP"
"6","(-3125,3425)","0","mstr_standard","I133";
;
CDS_LIB"mstr_standard"
BODY_TYPE"PLUMBING"
HDL_TAP"TRUE";
"B \NAC \NWC"7;
"S \NAC"
BN"0"49;
%"TAP"
"6","(-3125,3375)","0","mstr_standard","I134";
;
CDS_LIB"mstr_standard"
BODY_TYPE"PLUMBING"
HDL_TAP"TRUE";
"B \NAC \NWC"11;
"S \NAC"
BN"1"50;
%"TAP"
"6","(-3125,3325)","0","mstr_standard","I135";
;
CDS_LIB"mstr_standard"
BODY_TYPE"PLUMBING"
HDL_TAP"TRUE";
"B \NAC \NWC"11;
"S \NAC"
BN"0"51;
%"TAP"
"6","(-3125,2375)","0","mstr_standard","I138";
;
CDS_LIB"mstr_standard"
BODY_TYPE"PLUMBING"
HDL_TAP"TRUE";
"B \NAC \NWC"9;
"S \NAC"
BN"6"46;
%"TAP"
"6","(-3125,2325)","0","mstr_standard","I139";
;
CDS_LIB"mstr_standard"
BODY_TYPE"PLUMBING"
HDL_TAP"TRUE";
"B \NAC \NWC"9;
"S \NAC"
BN"7"59;
%"TAP"
"6","(700,4550)","2","mstr_standard","I14";
;
CDS_LIB"mstr_standard"
BODY_TYPE"PLUMBING"
HDL_TAP"TRUE";
"B \NAC \NWC"2;
"S \NAC"
BN"12"171;
%"TAP"
"6","(-3125,2275)","0","mstr_standard","I140";
;
CDS_LIB"mstr_standard"
BODY_TYPE"PLUMBING"
HDL_TAP"TRUE";
"B \NAC \NWC"9;
"S \NAC"
BN"4"58;
%"TAP"
"6","(-3125,2225)","0","mstr_standard","I141";
;
CDS_LIB"mstr_standard"
BODY_TYPE"PLUMBING"
HDL_TAP"TRUE";
"B \NAC \NWC"9;
"S \NAC"
BN"5"57;
%"TAP"
"6","(-3125,2075)","0","mstr_standard","I142";
;
CDS_LIB"mstr_standard"
BODY_TYPE"PLUMBING"
HDL_TAP"TRUE";
"B \NAC \NWC"9;
"S \NAC"
BN"0"54;
%"TAP"
"6","(-3125,2125)","0","mstr_standard","I143";
;
CDS_LIB"mstr_standard"
BODY_TYPE"PLUMBING"
HDL_TAP"TRUE";
"B \NAC \NWC"9;
"S \NAC"
BN"3"55;
%"TAP"
"6","(-3125,2175)","0","mstr_standard","I144";
;
CDS_LIB"mstr_standard"
BODY_TYPE"PLUMBING"
HDL_TAP"TRUE";
"B \NAC \NWC"9;
"S \NAC"
BN"2"56;
%"TAP"
"6","(-3125,2025)","0","mstr_standard","I145";
;
CDS_LIB"mstr_standard"
BODY_TYPE"PLUMBING"
HDL_TAP"TRUE";
"B \NAC \NWC"9;
"S \NAC"
BN"1"33;
%"TAP"
"6","(700,4650)","2","mstr_standard","I15";
;
CDS_LIB"mstr_standard"
BODY_TYPE"PLUMBING"
HDL_TAP"TRUE";
"B \NAC \NWC"2;
"S \NAC"
BN"13"169;
%"TAP"
"6","(-3125,3225)","0","mstr_standard","I152";
;
CDS_LIB"mstr_standard"
BODY_TYPE"PLUMBING"
HDL_TAP"TRUE";
"B \NAC \NWC"6;
"S \NAC"
BN"1"52;
%"TAP"
"6","(-3125,3125)","0","mstr_standard","I153";
;
CDS_LIB"mstr_standard"
BODY_TYPE"PLUMBING"
HDL_TAP"TRUE";
"B \NAC \NWC"6;
"S \NAC"
BN"0"73;
%"TAP"
"6","(-3325,3175)","0","mstr_standard","I156";
;
CDS_LIB"mstr_standard"
BODY_TYPE"PLUMBING"
HDL_TAP"TRUE";
"B \NAC \NWC"5;
"S \NAC"
BN"1"74;
%"TAP"
"6","(-3325,3075)","0","mstr_standard","I157";
;
CDS_LIB"mstr_standard"
BODY_TYPE"PLUMBING"
HDL_TAP"TRUE";
"B \NAC \NWC"5;
"S \NAC"
BN"0"72;
%"TAP"
"6","(-3125,2925)","0","mstr_standard","I158";
;
CDS_LIB"mstr_standard"
BODY_TYPE"PLUMBING"
HDL_TAP"TRUE";
"B \NAC \NWC"8;
"S \NAC"
BN"3"70;
%"TAP"
"6","(-3125,2875)","0","mstr_standard","I159";
;
CDS_LIB"mstr_standard"
BODY_TYPE"PLUMBING"
HDL_TAP"TRUE";
"B \NAC \NWC"8;
"S \NAC"
BN"2"69;
%"PVDDQ_GHJ"
"1","(-1350,2500)","0","mstr_symbols","I16";
;
VOLTAGE"1.2V"
BOM_COST"MEM"
CDS_LIB"mstr_symbols"
BODY_TYPE"PLUMBING"
ROOM"DDR4_CH_G"
HDL_POWER"PVDDQ_GHJ";
"G\NAC"13;
%"TAP"
"6","(-3125,2825)","0","mstr_standard","I160";
;
CDS_LIB"mstr_standard"
BODY_TYPE"PLUMBING"
HDL_TAP"TRUE";
"B \NAC \NWC"8;
"S \NAC"
BN"1"68;
%"TAP"
"6","(-3125,2775)","0","mstr_standard","I161";
;
CDS_LIB"mstr_standard"
BODY_TYPE"PLUMBING"
HDL_TAP"TRUE";
"B \NAC \NWC"8;
"S \NAC"
BN"0"42;
%"TAP"
"6","(-3125,2675)","0","mstr_standard","I162";
;
CDS_LIB"mstr_standard"
BODY_TYPE"PLUMBING"
HDL_TAP"TRUE";
"B \NAC \NWC"10;
"S \NAC"
BN"1"53;
%"TAP"
"6","(-3125,2625)","0","mstr_standard","I165";
;
CDS_LIB"mstr_standard"
BODY_TYPE"PLUMBING"
HDL_TAP"TRUE";
"B \NAC \NWC"10;
"S \NAC"
BN"0"43;
%"TAP"
"6","(-3125,2525)","0","mstr_standard","I166";
;
CDS_LIB"mstr_standard"
BODY_TYPE"PLUMBING"
HDL_TAP"TRUE";
"B \NAC \NWC"12;
"S \NAC"
BN"1"44;
%"TAP"
"6","(-3125,2475)","0","mstr_standard","I168";
;
CDS_LIB"mstr_standard"
BODY_TYPE"PLUMBING"
HDL_TAP"TRUE";
"B \NAC \NWC"12;
"S \NAC"
BN"0"45;
%"PVTT_GHJ"
"1","(-1150,2650)","0","mstr_symbols","I17";
;
VOLTAGE"0.6V"
BOM_COST"MEM"
CDS_LIB"mstr_symbols"
BODY_TYPE"PLUMBING"
ROOM"DDR4_CH_G"
HDL_POWER"PVTT_GHJ";
"G\NAC"14;
%"SCONN288_H44441004"
"4","(-300,1950)","0","mstr_sconn","I171";
;
CDS_SEC"4"
LOCATION"J1G1"
PART_NUMBER"H44441-004"
MATERIAL"SCONN"
PACK_TYPE"PIP"
BOM_COST"MEM"
CDS_LIB"mstr_sconn"
SEC_TYPE"PIP"
SEC"4"
CDS_LOCATION"J1G1"
ROOM"DDR4_CH_G";
"VPP<4>"
$PN"142"18;
"VTT<1>"
$PN"77"14;
"VPP<0>"
$PN"287"18;
"VPP<1>"
$PN"286"18;
"VPP<2>"
$PN"288"18;
"VPP<3>"
$PN"143"18;
"VDD<1>"
$PN"233"13;
"VDD<2>"
$PN"231"13;
"VDD<3>"
$PN"229"13;
"VDD<4>"
$PN"226"13;
"VDD<5>"
$PN"223"13;
"VDD<7>"
$PN"217"13;
"VDD<8>"
$PN"215"13;
"VDD<9>"
$PN"212"13;
"VDD<11>"
$PN"206"13;
"VDD<12>"
$PN"204"13;
"VDD<14>"
$PN"90"13;
"VDD<15>"
$PN"88"13;
"VDD<17>"
$PN"83"13;
"VDD<18>"
$PN"80"13;
"VDD<20>"
$PN"73"13;
"VDD<21>"
$PN"70"13;
"VDD<22>"
$PN"67"13;
"VDD<24>"
$PN"61"13;
"12V<0>"
$PN"145"20;
"12V<1>"
$PN"1"20;
"VTT<0>"
$PN"221"14;
"VDD<25>"
$PN"59"13;
"VDD<23>"
$PN"64"13;
"VDD<19>"
$PN"76"13;
"VDD<16>"
$PN"85"13;
"VDD<13>"
$PN"92"13;
"VDD<10>"
$PN"209"13;
"VDD<6>"
$PN"220"13;
"VDD<0>"
$PN"236"13;
%"GND"
"1","(2500,900)","2","mstr_symbols","I172";
;
VOLTAGE"0"
SIZE"1B"
CDS_LIB"mstr_symbols"
BOM_COST"MEM"
BODY_TYPE"PLUMBING"
ROOM"DDR4_CH_G"
HDL_POWER"GND";
"A\NAC"15;
%"GND"
"1","(-5075,1425)","2","mstr_symbols","I177";
;
VOLTAGE"0"
SIZE"1B"
CDS_LIB"mstr_symbols"
BOM_COST"MEM"
BODY_TYPE"PLUMBING"
ROOM"DDR4_CH_G"
HDL_POWER"GND";
"A\NAC"16;
%"GND"
"1","(-4425,825)","0","mstr_symbols","I180";
;
VOLTAGE"0"
SIZE"1B"
CDS_LIB"mstr_symbols"
BOM_COST"MEM"
BODY_TYPE"PLUMBING"
ROOM"DDR4_CH_G"
HDL_POWER"GND";
"A\NAC"17;
%"CAP_A"
"1","(-4425,1075)","2","dev_discrete","I181";
;
LOCATION"C1F22"
PART_NUMBER"A36096-045"
VALUE"0.01UF"
TOLERANCE"10%"
PACK_TYPE"0402V"
VOLTAGE"25V"
MATERIAL"X7R"
CDS_LOCATION"C1F22"
BOM_COST"MEM"
CDS_LIB"dev_discrete"
CDS_SEC"1"
$SEC"1"
ROOM"DDR4_CH_G";
"B"
$PN"2"17;
"A"
$PN"1"30;
%"PVPP_GHJ"
"1","(-1000,2950)","0","mstr_symbols","I182";
;
VOLTAGE"2.5V"
BOM_COST"MEM"
CDS_LIB"mstr_symbols"
BODY_TYPE"PLUMBING"
ROOM"DDR4_CH_G"
HDL_POWER"PVPP_GHJ";
"G\NAC"18;
%"PVPP_GHJ"
"1","(-5075,1775)","0","mstr_symbols","I183";
;
VOLTAGE"2.5V"
BOM_COST"MEM"
CDS_LIB"mstr_symbols"
BODY_TYPE"PLUMBING"
ROOM"DDR4_CH_H"
HDL_POWER"PVPP_GHJ";
"G\NAC"19;
%"TAP"
"6","(900,4400)","2","mstr_standard","I19";
;
CDS_LIB"mstr_standard"
BODY_TYPE"PLUMBING"
HDL_TAP"TRUE";
"B \NAC \NWC"1;
"S \NAC"
BN"11"174;
%"P12V_NVDIMM_GHJ"
"1","(400,2925)","0","mstr_symbols","I197";
;
VOLTAGE"12.0"
CDS_LIB"mstr_symbols"
BODY_TYPE"PLUMBING"
HDL_POWER"P12V_NVDIMM_GHJ";
"G\NAC"20;
%"TAP"
"6","(900,4200)","2","mstr_standard","I20";
;
CDS_LIB"mstr_standard"
BODY_TYPE"PLUMBING"
HDL_TAP"TRUE";
"B \NAC \NWC"1;
"S \NAC"
BN"9"159;
%"TAP"
"6","(900,4300)","2","mstr_standard","I21";
;
CDS_LIB"mstr_standard"
BODY_TYPE"PLUMBING"
HDL_TAP"TRUE";
"B \NAC \NWC"1;
"S \NAC"
BN"10"176;
%"TAP"
"6","(900,4100)","2","mstr_standard","I22";
;
CDS_LIB"mstr_standard"
BODY_TYPE"PLUMBING"
HDL_TAP"TRUE";
"B \NAC \NWC"1;
"S \NAC"
BN"8"161;
%"TAP"
"6","(900,4000)","2","mstr_standard","I23";
;
CDS_LIB"mstr_standard"
BODY_TYPE"PLUMBING"
HDL_TAP"TRUE";
"B \NAC \NWC"1;
"S \NAC"
BN"7"23;
%"TAP"
"6","(700,4350)","2","mstr_standard","I24";
;
CDS_LIB"mstr_standard"
BODY_TYPE"PLUMBING"
HDL_TAP"TRUE";
"B \NAC \NWC"2;
"S \NAC"
BN"10"175;
%"TAP"
"6","(700,4250)","2","mstr_standard","I25";
;
CDS_LIB"mstr_standard"
BODY_TYPE"PLUMBING"
HDL_TAP"TRUE";
"B \NAC \NWC"2;
"S \NAC"
BN"9"158;
%"TAP"
"6","(700,3950)","2","mstr_standard","I26";
;
CDS_LIB"mstr_standard"
BODY_TYPE"PLUMBING"
HDL_TAP"TRUE";
"B \NAC \NWC"2;
"S \NAC"
BN"6"144;
%"TAP"
"6","(700,4050)","2","mstr_standard","I27";
;
CDS_LIB"mstr_standard"
BODY_TYPE"PLUMBING"
HDL_TAP"TRUE";
"B \NAC \NWC"2;
"S \NAC"
BN"7"143;
%"TAP"
"6","(700,4150)","2","mstr_standard","I28";
;
CDS_LIB"mstr_standard"
BODY_TYPE"PLUMBING"
HDL_TAP"TRUE";
"B \NAC \NWC"2;
"S \NAC"
BN"8"160;
%"TAP"
"6","(900,3900)","2","mstr_standard","I29";
;
CDS_LIB"mstr_standard"
BODY_TYPE"PLUMBING"
HDL_TAP"TRUE";
"B \NAC \NWC"1;
"S \NAC"
BN"6"29;
%"TAP"
"6","(900,5000)","2","mstr_standard","I3";
;
CDS_LIB"mstr_standard"
BODY_TYPE"PLUMBING"
HDL_TAP"TRUE";
"B \NAC \NWC"1;
"S \NAC"
BN"17"162;
%"TAP"
"6","(900,3700)","2","mstr_standard","I30";
;
CDS_LIB"mstr_standard"
BODY_TYPE"PLUMBING"
HDL_TAP"TRUE";
"B \NAC \NWC"1;
"S \NAC"
BN"4"148;
%"TAP"
"6","(900,3800)","2","mstr_standard","I31";
;
CDS_LIB"mstr_standard"
BODY_TYPE"PLUMBING"
HDL_TAP"TRUE";
"B \NAC \NWC"1;
"S \NAC"
BN"5"146;
%"TAP"
"6","(900,3500)","2","mstr_standard","I32";
;
CDS_LIB"mstr_standard"
BODY_TYPE"PLUMBING"
HDL_TAP"TRUE";
"B \NAC \NWC"1;
"S \NAC"
BN"2"152;
%"TAP"
"6","(900,3600)","2","mstr_standard","I33";
;
CDS_LIB"mstr_standard"
BODY_TYPE"PLUMBING"
HDL_TAP"TRUE";
"B \NAC \NWC"1;
"S \NAC"
BN"3"150;
%"TAP"
"6","(700,3750)","2","mstr_standard","I34";
;
CDS_LIB"mstr_standard"
BODY_TYPE"PLUMBING"
HDL_TAP"TRUE";
"B \NAC \NWC"2;
"S \NAC"
BN"4"147;
%"TAP"
"6","(700,3850)","2","mstr_standard","I35";
;
CDS_LIB"mstr_standard"
BODY_TYPE"PLUMBING"
HDL_TAP"TRUE";
"B \NAC \NWC"2;
"S \NAC"
BN"5"145;
%"TAP"
"6","(700,3550)","2","mstr_standard","I36";
;
CDS_LIB"mstr_standard"
BODY_TYPE"PLUMBING"
HDL_TAP"TRUE";
"B \NAC \NWC"2;
"S \NAC"
BN"2"151;
%"TAP"
"6","(700,3450)","2","mstr_standard","I37";
;
CDS_LIB"mstr_standard"
BODY_TYPE"PLUMBING"
HDL_TAP"TRUE";
"B \NAC \NWC"2;
"S \NAC"
BN"1"153;
%"TAP"
"6","(700,3650)","2","mstr_standard","I38";
;
CDS_LIB"mstr_standard"
BODY_TYPE"PLUMBING"
HDL_TAP"TRUE";
"B \NAC \NWC"2;
"S \NAC"
BN"3"149;
%"TAP"
"6","(900,3300)","2","mstr_standard","I39";
;
CDS_LIB"mstr_standard"
BODY_TYPE"PLUMBING"
HDL_TAP"TRUE";
"B \NAC \NWC"1;
"S \NAC"
BN"0"156;
%"TAP"
"6","(700,5050)","2","mstr_standard","I4";
;
CDS_LIB"mstr_standard"
BODY_TYPE"PLUMBING"
HDL_TAP"TRUE";
"B \NAC \NWC"2;
"S \NAC"
BN"17"157;
%"TAP"
"6","(900,3400)","2","mstr_standard","I40";
;
CDS_LIB"mstr_standard"
BODY_TYPE"PLUMBING"
HDL_TAP"TRUE";
"B \NAC \NWC"1;
"S \NAC"
BN"1"154;
%"TAP"
"6","(700,3350)","2","mstr_standard","I41";
;
CDS_LIB"mstr_standard"
BODY_TYPE"PLUMBING"
HDL_TAP"TRUE";
"B \NAC \NWC"2;
"S \NAC"
BN"0"155;
%"SCONN288_H44441004"
"3","(1800,2200)","0","mstr_sconn","I43";
;
CDS_SEC"3"
LOCATION"J1G1"
PART_NUMBER"H44441-004"
MATERIAL"SCONN"
PACK_TYPE"PIP"
BOM_COST"MEM"
CDS_LIB"mstr_sconn"
SEC_TYPE"PIP"
SEC"3"
CDS_LOCATION"J1G1"
ROOM"DDR4_CH_G";
"VSS<93>"
$PN"2"21;
"VSS<92>"
$PN"4"21;
"VSS<91>"
$PN"6"21;
"VSS<90>"
$PN"9"21;
"VSS<89>"
$PN"11"21;
"VSS<88>"
$PN"13"21;
"VSS<0>"
$PN"283"15;
"VSS<1>"
$PN"281"15;
"VSS<2>"
$PN"279"15;
"VSS<3>"
$PN"276"15;
"VSS<4>"
$PN"274"15;
"VSS<5>"
$PN"272"15;
"VSS<6>"
$PN"270"15;
"VSS<7>"
$PN"268"15;
"VSS<8>"
$PN"265"15;
"VSS<9>"
$PN"263"15;
"VSS<10>"
$PN"261"15;
"VSS<11>"
$PN"259"15;
"VSS<12>"
$PN"257"15;
"VSS<13>"
$PN"254"15;
"VSS<14>"
$PN"252"15;
"VSS<15>"
$PN"250"15;
"VSS<16>"
$PN"248"15;
"VSS<17>"
$PN"246"15;
"VSS<18>"
$PN"243"15;
"VSS<19>"
$PN"241"15;
"VSS<20>"
$PN"239"15;
"VSS<21>"
$PN"202"15;
"VSS<22>"
$PN"200"15;
"VSS<23>"
$PN"198"15;
"VSS<24>"
$PN"195"15;
"VSS<25>"
$PN"193"15;
"VSS<26>"
$PN"191"15;
"VSS<27>"
$PN"189"15;
"VSS<28>"
$PN"187"15;
"VSS<29>"
$PN"184"15;
"VSS<30>"
$PN"182"15;
"VSS<31>"
$PN"180"15;
"VSS<32>"
$PN"178"15;
"VSS<33>"
$PN"176"15;
"VSS<34>"
$PN"173"15;
"VSS<35>"
$PN"171"15;
"VSS<36>"
$PN"169"15;
"VSS<37>"
$PN"167"15;
"VSS<38>"
$PN"165"15;
"VSS<39>"
$PN"162"15;
"VSS<40>"
$PN"160"15;
"VSS<41>"
$PN"158"15;
"VSS<42>"
$PN"156"15;
"VSS<43>"
$PN"154"15;
"VSS<44>"
$PN"151"15;
"VSS<47>"
$PN"138"21;
"VSS<48>"
$PN"136"21;
"VSS<49>"
$PN"134"21;
"VSS<50>"
$PN"131"21;
"VSS<51>"
$PN"129"21;
"VSS<52>"
$PN"127"21;
"VSS<53>"
$PN"125"21;
"VSS<54>"
$PN"123"21;
"VSS<55>"
$PN"120"21;
"VSS<56>"
$PN"118"21;
"VSS<57>"
$PN"116"21;
"VSS<58>"
$PN"114"21;
"VSS<59>"
$PN"112"21;
"VSS<60>"
$PN"109"21;
"VSS<61>"
$PN"107"21;
"VSS<62>"
$PN"105"21;
"VSS<63>"
$PN"103"21;
"VSS<64>"
$PN"101"21;
"VSS<65>"
$PN"98"21;
"VSS<66>"
$PN"96"21;
"VSS<67>"
$PN"94"21;
"VSS<68>"
$PN"57"21;
"VSS<69>"
$PN"55"21;
"VSS<70>"
$PN"53"21;
"VSS<71>"
$PN"50"21;
"VSS<72>"
$PN"48"21;
"VSS<73>"
$PN"46"21;
"VSS<74>"
$PN"44"21;
"VSS<75>"
$PN"42"21;
"VSS<76>"
$PN"39"21;
"VSS<77>"
$PN"37"21;
"VSS<78>"
$PN"35"21;
"VSS<79>"
$PN"33"21;
"VSS<80>"
$PN"31"21;
"VSS<81>"
$PN"28"21;
"VSS<82>"
$PN"26"21;
"VSS<83>"
$PN"24"21;
"VSS<84>"
$PN"22"21;
"VSS<85>"
$PN"20"21;
"VSS<86>"
$PN"17"21;
"VSS<87>"
$PN"15"21;
"VSS<45>"
$PN"149"15;
"VSS<46>"
$PN"147"15;
%"GND"
"1","(1100,900)","2","mstr_symbols","I44";
;
VOLTAGE"0"
SIZE"1B"
CDS_LIB"mstr_symbols"
BOM_COST"MEM"
BODY_TYPE"PLUMBING"
ROOM"DDR4_CH_G"
HDL_POWER"GND";
"A\NAC"21;
%"TAP"
"6","(-1625,4375)","2","mstr_standard","I46";
;
CDS_LIB"mstr_standard"
BODY_TYPE"PLUMBING"
HDL_TAP"TRUE";
"B \NAC \NWC"3;
"S \NAC"
BN"63"139;
%"TAP"
"6","(-1625,4425)","2","mstr_standard","I47";
;
CDS_LIB"mstr_standard"
BODY_TYPE"PLUMBING"
HDL_TAP"TRUE";
"B \NAC \NWC"3;
"S \NAC"
BN"62"138;
%"TAP"
"6","(-1625,4275)","2","mstr_standard","I48";
;
CDS_LIB"mstr_standard"
BODY_TYPE"PLUMBING"
HDL_TAP"TRUE";
"B \NAC \NWC"3;
"S \NAC"
BN"61"28;
%"TAP"
"6","(-1625,4325)","2","mstr_standard","I49";
;
CDS_LIB"mstr_standard"
BODY_TYPE"PLUMBING"
HDL_TAP"TRUE";
"B \NAC \NWC"3;
"S \NAC"
BN"60"140;
%"TAP"
"6","(900,4800)","2","mstr_standard","I5";
;
CDS_LIB"mstr_standard"
BODY_TYPE"PLUMBING"
HDL_TAP"TRUE";
"B \NAC \NWC"1;
"S \NAC"
BN"15"166;
%"TAP"
"6","(-1625,4225)","2","mstr_standard","I50";
;
CDS_LIB"mstr_standard"
BODY_TYPE"PLUMBING"
HDL_TAP"TRUE";
"B \NAC \NWC"3;
"S \NAC"
BN"58"25;
%"TAP"
"6","(-1625,4175)","2","mstr_standard","I51";
;
CDS_LIB"mstr_standard"
BODY_TYPE"PLUMBING"
HDL_TAP"TRUE";
"B \NAC \NWC"3;
"S \NAC"
BN"59"141;
%"TAP"
"6","(-1625,4125)","2","mstr_standard","I52";
;
CDS_LIB"mstr_standard"
BODY_TYPE"PLUMBING"
HDL_TAP"TRUE";
"B \NAC \NWC"3;
"S \NAC"
BN"56"142;
%"TAP"
"6","(-1625,4075)","2","mstr_standard","I53";
;
CDS_LIB"mstr_standard"
BODY_TYPE"PLUMBING"
HDL_TAP"TRUE";
"B \NAC \NWC"3;
"S \NAC"
BN"57"127;
%"TAP"
"6","(-1625,4025)","2","mstr_standard","I54";
;
CDS_LIB"mstr_standard"
BODY_TYPE"PLUMBING"
HDL_TAP"TRUE";
"B \NAC \NWC"3;
"S \NAC"
BN"54"126;
%"TAP"
"6","(-1625,3875)","2","mstr_standard","I55";
;
CDS_LIB"mstr_standard"
BODY_TYPE"PLUMBING"
HDL_TAP"TRUE";
"B \NAC \NWC"3;
"S \NAC"
BN"53"123;
%"TAP"
"6","(-1625,3975)","2","mstr_standard","I56";
;
CDS_LIB"mstr_standard"
BODY_TYPE"PLUMBING"
HDL_TAP"TRUE";
"B \NAC \NWC"3;
"S \NAC"
BN"55"125;
%"TAP"
"6","(-1625,3925)","2","mstr_standard","I57";
;
CDS_LIB"mstr_standard"
BODY_TYPE"PLUMBING"
HDL_TAP"TRUE";
"B \NAC \NWC"3;
"S \NAC"
BN"52"124;
%"TAP"
"6","(-1625,3825)","2","mstr_standard","I58";
;
CDS_LIB"mstr_standard"
BODY_TYPE"PLUMBING"
HDL_TAP"TRUE";
"B \NAC \NWC"3;
"S \NAC"
BN"50"122;
%"TAP"
"6","(-1625,3775)","2","mstr_standard","I59";
;
CDS_LIB"mstr_standard"
BODY_TYPE"PLUMBING"
HDL_TAP"TRUE";
"B \NAC \NWC"3;
"S \NAC"
BN"51"128;
%"TAP"
"6","(900,4900)","2","mstr_standard","I6";
;
CDS_LIB"mstr_standard"
BODY_TYPE"PLUMBING"
HDL_TAP"TRUE";
"B \NAC \NWC"1;
"S \NAC"
BN"16"164;
%"TAP"
"6","(-1625,3725)","2","mstr_standard","I60";
;
CDS_LIB"mstr_standard"
BODY_TYPE"PLUMBING"
HDL_TAP"TRUE";
"B \NAC \NWC"3;
"S \NAC"
BN"48"129;
%"TAP"
"6","(-1625,3575)","2","mstr_standard","I61";
;
CDS_LIB"mstr_standard"
BODY_TYPE"PLUMBING"
HDL_TAP"TRUE";
"B \NAC \NWC"3;
"S \NAC"
BN"47"116;
%"TAP"
"6","(-1625,3675)","2","mstr_standard","I62";
;
CDS_LIB"mstr_standard"
BODY_TYPE"PLUMBING"
HDL_TAP"TRUE";
"B \NAC \NWC"3;
"S \NAC"
BN"49"130;
%"TAP"
"6","(-1625,3625)","2","mstr_standard","I63";
;
CDS_LIB"mstr_standard"
BODY_TYPE"PLUMBING"
HDL_TAP"TRUE";
"B \NAC \NWC"3;
"S \NAC"
BN"46"121;
%"TAP"
"6","(-1625,3525)","2","mstr_standard","I64";
;
CDS_LIB"mstr_standard"
BODY_TYPE"PLUMBING"
HDL_TAP"TRUE";
"B \NAC \NWC"3;
"S \NAC"
BN"44"115;
%"TAP"
"6","(-1625,3475)","2","mstr_standard","I65";
;
CDS_LIB"mstr_standard"
BODY_TYPE"PLUMBING"
HDL_TAP"TRUE";
"B \NAC \NWC"3;
"S \NAC"
BN"45"117;
%"SCONN288_H44441004"
"2","(0,4200)","0","mstr_sconn","I66";
;
CDS_SEC"2"
LOCATION"J1G1"
PART_NUMBER"H44441-004"
MATERIAL"SCONN"
PACK_TYPE"PIP"
BOM_COST"MEM"
CDS_LIB"mstr_sconn"
SEC_TYPE"PIP"
SEC"2"
CDS_LOCATION"J1G1"
ROOM"DDR4_CH_G";
"DQS17P"
$PN"51"157;
"DQS9P"
$PN"7"158;
"DQS9N"
$PN"8"159;
"DQS8P"
$PN"197"160;
"DQS8N"
$PN"196"161;
"DQS7P"
$PN"278"143;
"DQS7N"
$PN"277"23;
"DQS6P"
$PN"267"144;
"DQS6N"
$PN"266"29;
"DQS5P"
$PN"256"145;
"DQS5N"
$PN"255"146;
"DQS4P"
$PN"245"147;
"DQS4N"
$PN"244"148;
"DQS3P"
$PN"186"149;
"DQS3N"
$PN"185"150;
"DQS2P"
$PN"175"151;
"DQS2N"
$PN"174"152;
"DQS1P"
$PN"164"153;
"DQS1N"
$PN"163"154;
"DQS17N"
$PN"52"162;
"DQS16P"
$PN"132"163;
"DQS16N"
$PN"133"164;
"DQS15P"
$PN"121"165;
"DQS15N"
$PN"122"166;
"DQS14P"
$PN"110"167;
"DQS14N"
$PN"111"168;
"DQS13P"
$PN"99"169;
"DQS13N"
$PN"100"170;
"DQS12P"
$PN"40"171;
"DQS12N"
$PN"41"172;
"DQS11P"
$PN"29"173;
"DQS11N"
$PN"30"174;
"DQS10P"
$PN"18"175;
"DQS10N"
$PN"19"176;
"DQS0P"
$PN"153"155;
"DQS0N"
$PN"152"156;
%"TAP"
"6","(-1625,3325)","2","mstr_standard","I67";
;
CDS_LIB"mstr_standard"
BODY_TYPE"PLUMBING"
HDL_TAP"TRUE";
"B \NAC \NWC"3;
"S \NAC"
BN"40"119;
%"TAP"
"6","(-1625,3375)","2","mstr_standard","I68";
;
CDS_LIB"mstr_standard"
BODY_TYPE"PLUMBING"
HDL_TAP"TRUE";
"B \NAC \NWC"3;
"S \NAC"
BN"43"114;
%"TAP"
"6","(-1625,3425)","2","mstr_standard","I69";
;
CDS_LIB"mstr_standard"
BODY_TYPE"PLUMBING"
HDL_TAP"TRUE";
"B \NAC \NWC"3;
"S \NAC"
BN"42"118;
%"TAP"
"6","(900,4600)","2","mstr_standard","I7";
;
CDS_LIB"mstr_standard"
BODY_TYPE"PLUMBING"
HDL_TAP"TRUE";
"B \NAC \NWC"1;
"S \NAC"
BN"13"170;
%"TAP"
"6","(-1625,3225)","2","mstr_standard","I70";
;
CDS_LIB"mstr_standard"
BODY_TYPE"PLUMBING"
HDL_TAP"TRUE";
"B \NAC \NWC"3;
"S \NAC"
BN"38"120;
%"TAP"
"6","(-1625,3275)","2","mstr_standard","I71";
;
CDS_LIB"mstr_standard"
BODY_TYPE"PLUMBING"
HDL_TAP"TRUE";
"B \NAC \NWC"3;
"S \NAC"
BN"41"113;
%"TAP"
"6","(-1625,3075)","2","mstr_standard","I72";
;
CDS_LIB"mstr_standard"
BODY_TYPE"PLUMBING"
HDL_TAP"TRUE";
"B \NAC \NWC"3;
"S \NAC"
BN"37"111;
%"TAP"
"6","(-1625,3125)","2","mstr_standard","I73";
;
CDS_LIB"mstr_standard"
BODY_TYPE"PLUMBING"
HDL_TAP"TRUE";
"B \NAC \NWC"3;
"S \NAC"
BN"36"112;
%"TAP"
"6","(-1625,3175)","2","mstr_standard","I74";
;
CDS_LIB"mstr_standard"
BODY_TYPE"PLUMBING"
HDL_TAP"TRUE";
"B \NAC \NWC"3;
"S \NAC"
BN"39"110;
%"TAP"
"6","(-1625,2975)","2","mstr_standard","I75";
;
CDS_LIB"mstr_standard"
BODY_TYPE"PLUMBING"
HDL_TAP"TRUE";
"B \NAC \NWC"3;
"S \NAC"
BN"35"106;
%"TAP"
"6","(-1625,3025)","2","mstr_standard","I76";
;
CDS_LIB"mstr_standard"
BODY_TYPE"PLUMBING"
HDL_TAP"TRUE";
"B \NAC \NWC"3;
"S \NAC"
BN"34"101;
%"TAP"
"6","(-1625,2825)","2","mstr_standard","I77";
;
CDS_LIB"mstr_standard"
BODY_TYPE"PLUMBING"
HDL_TAP"TRUE";
"B \NAC \NWC"3;
"S \NAC"
BN"30"103;
%"TAP"
"6","(-1625,2875)","2","mstr_standard","I78";
;
CDS_LIB"mstr_standard"
BODY_TYPE"PLUMBING"
HDL_TAP"TRUE";
"B \NAC \NWC"3;
"S \NAC"
BN"33"104;
%"TAP"
"6","(-1625,2925)","2","mstr_standard","I79";
;
CDS_LIB"mstr_standard"
BODY_TYPE"PLUMBING"
HDL_TAP"TRUE";
"B \NAC \NWC"3;
"S \NAC"
BN"32"105;
%"TAP"
"6","(900,4700)","2","mstr_standard","I8";
;
CDS_LIB"mstr_standard"
BODY_TYPE"PLUMBING"
HDL_TAP"TRUE";
"B \NAC \NWC"1;
"S \NAC"
BN"14"168;
%"TAP"
"6","(-1625,2775)","2","mstr_standard","I80";
;
CDS_LIB"mstr_standard"
BODY_TYPE"PLUMBING"
HDL_TAP"TRUE";
"B \NAC \NWC"3;
"S \NAC"
BN"31"102;
%"TAP"
"6","(-1625,2725)","2","mstr_standard","I81";
;
CDS_LIB"mstr_standard"
BODY_TYPE"PLUMBING"
HDL_TAP"TRUE";
"B \NAC \NWC"3;
"S \NAC"
BN"28"108;
%"TAP"
"6","(-1625,2575)","2","mstr_standard","I82";
;
CDS_LIB"mstr_standard"
BODY_TYPE"PLUMBING"
HDL_TAP"TRUE";
"B \NAC \NWC"3;
"S \NAC"
BN"27"100;
%"TAP"
"6","(-1625,2675)","2","mstr_standard","I83";
;
CDS_LIB"mstr_standard"
BODY_TYPE"PLUMBING"
HDL_TAP"TRUE";
"B \NAC \NWC"3;
"S \NAC"
BN"29"107;
%"TAP"
"6","(-1625,2625)","2","mstr_standard","I84";
;
CDS_LIB"mstr_standard"
BODY_TYPE"PLUMBING"
HDL_TAP"TRUE";
"B \NAC \NWC"3;
"S \NAC"
BN"26"109;
%"TAP"
"6","(-1625,2475)","2","mstr_standard","I85";
;
CDS_LIB"mstr_standard"
BODY_TYPE"PLUMBING"
HDL_TAP"TRUE";
"B \NAC \NWC"3;
"S \NAC"
BN"25"96;
%"TAP"
"6","(-1625,2525)","2","mstr_standard","I86";
;
CDS_LIB"mstr_standard"
BODY_TYPE"PLUMBING"
HDL_TAP"TRUE";
"B \NAC \NWC"3;
"S \NAC"
BN"24"97;
%"TAP"
"6","(-1625,2325)","2","mstr_standard","I87";
;
CDS_LIB"mstr_standard"
BODY_TYPE"PLUMBING"
HDL_TAP"TRUE";
"B \NAC \NWC"3;
"S \NAC"
BN"20"93;
%"TAP"
"6","(-1625,2425)","2","mstr_standard","I88";
;
CDS_LIB"mstr_standard"
BODY_TYPE"PLUMBING"
HDL_TAP"TRUE";
"B \NAC \NWC"3;
"S \NAC"
BN"22"95;
%"TAP"
"6","(-1625,2375)","2","mstr_standard","I89";
;
CDS_LIB"mstr_standard"
BODY_TYPE"PLUMBING"
HDL_TAP"TRUE";
"B \NAC \NWC"3;
"S \NAC"
BN"23"94;
%"TAP"
"6","(900,4500)","2","mstr_standard","I9";
;
CDS_LIB"mstr_standard"
BODY_TYPE"PLUMBING"
HDL_TAP"TRUE";
"B \NAC \NWC"1;
"S \NAC"
BN"12"172;
%"TAP"
"6","(-1625,2275)","2","mstr_standard","I90";
;
CDS_LIB"mstr_standard"
BODY_TYPE"PLUMBING"
HDL_TAP"TRUE";
"B \NAC \NWC"3;
"S \NAC"
BN"21"24;
%"TAP"
"6","(-1625,2225)","2","mstr_standard","I91";
;
CDS_LIB"mstr_standard"
BODY_TYPE"PLUMBING"
HDL_TAP"TRUE";
"B \NAC \NWC"3;
"S \NAC"
BN"18"92;
%"TAP"
"6","(-1625,2175)","2","mstr_standard","I92";
;
CDS_LIB"mstr_standard"
BODY_TYPE"PLUMBING"
HDL_TAP"TRUE";
"B \NAC \NWC"3;
"S \NAC"
BN"19"91;
%"TAP"
"6","(-1625,2125)","2","mstr_standard","I93";
;
CDS_LIB"mstr_standard"
BODY_TYPE"PLUMBING"
HDL_TAP"TRUE";
"B \NAC \NWC"3;
"S \NAC"
BN"16"99;
%"TAP"
"6","(-1625,2075)","2","mstr_standard","I94";
;
CDS_LIB"mstr_standard"
BODY_TYPE"PLUMBING"
HDL_TAP"TRUE";
"B \NAC \NWC"3;
"S \NAC"
BN"17"98;
%"TAP"
"6","(-1625,2025)","2","mstr_standard","I95";
;
CDS_LIB"mstr_standard"
BODY_TYPE"PLUMBING"
HDL_TAP"TRUE";
"B \NAC \NWC"3;
"S \NAC"
BN"14"81;
%"TAP"
"6","(-1625,1975)","2","mstr_standard","I96";
;
CDS_LIB"mstr_standard"
BODY_TYPE"PLUMBING"
HDL_TAP"TRUE";
"B \NAC \NWC"3;
"S \NAC"
BN"15"89;
%"TAP"
"6","(-1625,1875)","2","mstr_standard","I97";
;
CDS_LIB"mstr_standard"
BODY_TYPE"PLUMBING"
HDL_TAP"TRUE";
"B \NAC \NWC"3;
"S \NAC"
BN"13"87;
%"TAP"
"6","(-1625,1925)","2","mstr_standard","I98";
;
CDS_LIB"mstr_standard"
BODY_TYPE"PLUMBING"
HDL_TAP"TRUE";
"B \NAC \NWC"3;
"S \NAC"
BN"12"88;
%"TAP"
"6","(-1625,1825)","2","mstr_standard","I99";
;
CDS_LIB"mstr_standard"
BODY_TYPE"PLUMBING"
HDL_TAP"TRUE";
"B \NAC \NWC"3;
"S \NAC"
BN"10"86;
END.
